# BASEBOARD_FAB2 (Tioga Pass) — schematic parts with pin connectivity, parts 4650–4650 of 4751; source: Cadence DE-HDL packaged netlist (pstxprt.dat, pstxnet.dat, pstchip.dat)

U2D1  SKX_EXT_B  IC  pkg BGA1  page 55  (pins 2029-2366 of 3647)
  DC8  PE1_RX_DN(2)  IN  = TP_P3E_CPU1_PE1_MP_RXN<2>
  DC10  PE1_RX_DN(3)  IN  = TP_P3E_CPU1_PE1_MP_RXN<3>
  DC12  PE3_RX_DP(12)  IN  = P3E_CPU1_PE3_MP_RXN<12>
  DC14  VSS(272)  GROUND  = GND
  DC16  UPI2_TX_DN(9)  OUT  = TP_CPU1_UPI2_RSVD_DA16
  DC18  VCCIO(14)  POWER  = PVCCIO_CPU1
  DC20  UPI2_RX_DP(3)  IN  = GND
  DC22  UPI2_RX_DN(2)  IN  = GND
  DC24  VSS(271)  GROUND  = GND
  DC26  VSS(270)  GROUND  = GND
  DC28  DDR5_DQ(63)  BI  = M_M_DQ<63>
  DC30  DDR5_DQ(57)  BI  = M_M_DQ<57>
  DC32  VSS(269)  GROUND  = GND
  DC34  DDR5_DQ(55)  BI  = M_M_DQ<55>
  DC36  DDR5_DQ(49)  BI  = M_M_DQ<49>
  DC38  VSS(268)  GROUND  = GND
  DC40  DDR5_DQS_DP(13)  BI  = M_M_DQS_DP<13>
  DC42  VSS(267)  GROUND  = GND
  DC44  SVIDCLK(0)  OUT  = SVID_CLK0_CPU1
  DC46  RSVD(47)  BI  = TP_CPU1_RSVD_47
  DC48  DDR345_RCOMP(0)  BI  = A_CPU1_KLM_RCOMP0
  DC50  TEST_14  BI  = PD_CPU1_TEST14
  DC52  RSVD(46)  BI  = TP_CPU1_RSVD_46
  DC54  DDR5_MA(15)  OUT  = M_M_MA<15>
  DC56  DDR5_BA(1)  OUT  = M_M_BA<1>
  DC58  DDR5_MA(1)  OUT  = M_M_MA<1>
  DC60  DDR5_MA(7)  OUT  = M_M_MA<7>
  DC62  DDR5_ACT_N  OUT  = M_M_ACT_N
  DC64  VSS(266)  GROUND  = GND
  DC66  VSS(265)  GROUND  = GND
  DC68  VSS(264)  GROUND  = GND
  DC70  VSS(263)  GROUND  = GND
  DC72  PKGID(0)  BI  = FM_CPU1_PKGID0
  DC74  DDR5_DQ(12)  BI  = M_M_DQ<12>
  DC76  DDR5_DQ(9)  BI  = M_M_DQ<9>
  DC78  VSS(262)  GROUND  = GND
  DC80  DDR4_DQS_DN(10)  BI  = M_L_DQS_DN<10>
  DC82  DDR4_DQ(14)  BI  = M_L_DQ<14>
  DC84  VSS(261)  GROUND  = GND
  DC86  VSS(260)  GROUND  = GND
  DD3  PE1_TX_DP(2)  OUT  = TP_P3E_CPU1_PE1_MP_TXP<2>
  DD5  PE3_TX_DN(13)  OUT  = P3E_CPU1_PE3_MP_TXN<13>
  DD7  VCCIO(39)  POWER  = PVCCIO_CPU1
  DD9  PE1_RX_DP(4)  IN  = TP_P3E_CPU1_PE1_MP_RXP<4>
  DD11  VSS(259)  GROUND  = GND
  DD13  PE3_RX_DN(12)  IN  = P3E_CPU1_PE3_MP_RXP<12>
  DD15  UPI2_TX_DP(8)  OUT  = TP_CPU1_UPI2_RSVD_CV13
  DD17  UPI2_TX_DN(7)  OUT  = TP_CPU1_UPI2_RSVD_CU14
  DD19  UPI2_RX_DN(4)  IN  = GND
  DD21  UPI2_RX_DP(1)  IN  = GND
  DD23  VSS(258)  GROUND  = GND
  DD25  DDR4_DQ(58)  BI  = M_L_DQ<58>
  DD27  VSS(257)  GROUND  = GND
  DD29  DDR5_DQS_DN(7)  BI  = M_M_DQS_DN<7>
  DD31  VSS(256)  GROUND  = GND
  DD33  VSS(255)  GROUND  = GND
  DD35  DDR5_DQS_DN(6)  BI  = M_M_DQS_DN<6>
  DD37  VSS(254)  GROUND  = GND
  DD39  DDR5_DQ(38)  BI  = M_M_DQ<38>
  DD41  DDR5_DQ(32)  BI  = M_M_DQ<32>
  DD45  VCCD345(42)  POWER  = PVDDQ_KLM
  DD47  DDR345_RCOMP(1)  BI  = A_CPU1_KLM_RCOMP1
  DD49  DDR345_RCOMP(2)  BI  = A_CPU1_KLM_RCOMP2
  DD51  RSVD(45)  BI  = TP_CPU1_RSVD_45
  DD53  DDR5_MA(13)  OUT  = M_M_MA<13>
  DD55  DDR5_MA(10)  OUT  = M_M_MA<10>
  DD57  DDR5_MA(2)  OUT  = M_M_MA<2>
  DD59  DDR5_MA(8)  OUT  = M_M_MA<8>
  DD61  DDR5_ALERT_N  IN  = M_M_ALERT_N
  DD63  DDR5_CKE(1)  OUT  = M_M_CKE<1>
  DD65  DDR3_ECC(3)  BI  = M_K_ECC<3>
  DD67  DDR3_DQS_DP(8)  BI  = M_K_DQS_DP<8>
  DD69  DDR3_ECC(5)  BI  = M_K_ECC<5>
  DD71  VSS(253)  GROUND  = GND
  DD73  VSS(252)  GROUND  = GND
  DD75  VSS(251)  GROUND  = GND
  DD77  DDR5_DQS_DN(1)  BI  = M_M_DQS_DN<1>
  DD79  DDR4_DQS_DP(10)  BI  = M_L_DQS_DP<10>
  DD81  VSS(250)  GROUND  = GND
  DD83  VSS(249)  GROUND  = GND
  DD85  DDR3_DQ(12)  BI  = M_K_DQ<12>
  DE2  PE1_TX_DN(2)  OUT  = TP_P3E_CPU1_PE1_MP_TXN<2>
  DE4  PE1_TX_DN(3)  OUT  = TP_P3E_CPU1_PE1_MP_TXN<3>
  DE6  VSS(248)  GROUND  = GND
  DE8  VSS(247)  GROUND  = GND
  DE10  PE1_RX_DN(4)  IN  = TP_P3E_CPU1_PE1_MP_RXN<4>
  DE12  PE3_RX_DP(10)  IN  = P3E_CPU1_PE3_MP_RXP<10>
  DE14  VCCIO(13)  POWER  = PVCCIO_CPU1
  DE16  UPI2_TX_DP(7)  OUT  = TP_CPU1_UPI2_RSVD_CR14
  DE18  VSS(246)  GROUND  = GND
  DE20  VSS(245)  GROUND  = GND
  DE22  UPI2_RX_DN(1)  IN  = GND
  DE24  VSS(244)  GROUND  = GND
  DE26  DDR4_DQS_DP(16)  BI  = M_L_DQS_DP<16>
  DE28  VSS(243)  GROUND  = GND
  DE30  VSS(242)  GROUND  = GND
  DE32  DDR5_DQS_DP(14)  BI  = M_M_DQS_DP<14>
  DE34  VSS(241)  GROUND  = GND
  DE36  VSS(240)  GROUND  = GND
  DE38  DDR5_DQ(34)  BI  = M_M_DQ<34>
  DE40  DDR5_DQS_DN(13)  BI  = M_M_DQS_DN<13>
  DE42  DDR5_DQ(37)  BI  = M_M_DQ<37>
  DE44  SVIDALERT_N(0)  IN  = SVID_ALERT0_CPU1_N
  DE46  DDR5_MA(17)  OUT  = M_M_MA<17>
  DE48  VSS(1193)  GROUND  = GND
  DE50  VSS(1194)  GROUND  = GND
  DE52  VSS(1195)  GROUND  = GND
  DE54  VSS(1196)  GROUND  = GND
  DE56  VSS(1197)  GROUND  = GND
  DE58  VSS(1198)  GROUND  = GND
  DE60  VSS(1199)  GROUND  = GND
  DE62  VSS(1200)  GROUND  = GND
  DE64  VSS(239)  GROUND  = GND
  DE66  DDR3_ECC(7)  BI  = M_K_ECC<7>
  DE68  DDR3_ECC(1)  BI  = M_K_ECC<1>
  DE70  VSS(238)  GROUND  = GND
  DE72  VSS(237)  GROUND  = GND
  DE74  DDR5_DQ(8)  BI  = M_M_DQ<8>
  DE76  DDR5_DQS_DP(1)  BI  = M_M_DQS_DP<1>
  DE78  VSS(236)  GROUND  = GND
  DE80  DDR4_DQ(10)  BI  = M_L_DQ<10>
  DE82  DDR4_DQ(15)  BI  = M_L_DQ<15>
  DE84  DDR3_DQ(13)  BI  = M_K_DQ<13>
  DF3  PE1_TX_DP(4)  OUT  = TP_P3E_CPU1_PE1_MP_TXP<4>
  DF5  VSS(235)  GROUND  = GND
  DF7  VSS(234)  GROUND  = GND
  DF9  PE1_RX_DP(5)  IN  = TP_P3E_CPU1_PE1_MP_RXP<5>
  DF11  PE3_RX_DP(11)  IN  = P3E_CPU1_PE3_MP_RXP<11>
  DF13  VCCIO(41)  POWER  = PVCCIO_CPU1
  DF15  UPI2_TX_DN(8)  OUT  = TP_CPU1_UPI2_RSVD_CW14
  DF17  UPI2_TX_DP(6)  OUT  = TP_CPU1_UPI2_RSVD_CK13
  DF19  VSS(232)  GROUND  = GND
  DF21  VCCIO(48)  POWER  = PVCCIO_CPU1
  DF23  UPI2_RX_DN(0)  IN  = GND
  DF25  DDR4_DQ(62)  BI  = M_L_DQ<62>
  DF27  DDR4_DQ(56)  BI  = M_L_DQ<56>
  DF29  VSS(231)  GROUND  = GND
  DF31  DDR5_DQ(46)  BI  = M_M_DQ<46>
  DF33  DDR5_DQ(40)  BI  = M_M_DQ<40>
  DF35  VSS(230)  GROUND  = GND
  DF37  VSS(229)  GROUND  = GND
  DF39  VSS(228)  GROUND  = GND
  DF41  VSS(227)  GROUND  = GND
  DF45  DDR5_CID(2)  OUT  = M_M_C<2>
  DF47  DDR5_ODT(3)  OUT  = M_M_ODT<3>
  DF49  DDR5_CS_N(1)  OUT  = M_M_CS_N<1>
  DF51  DDR5_CS_N(4)  OUT  = M_M_CS_N<4>
  DF53  DDR5_MA(0)  OUT  = M_M_MA<0>
  DF55  DDR5_CLK_DN(1)  OUT  = M_M_CLK_DN<1>
  DF57  DDR5_CLK_DN(3)  OUT  = M_M_CLK_DN<3>
  DF59  DDR5_MA(5)  OUT  = M_M_MA<5>
  DF61  DDR5_BG(1)  OUT  = M_M_BG<1>
  DF63  DDR5_CKE(3)  OUT  = M_M_CKE<3>
  DF65  VSS(226)  GROUND  = GND
  DF67  DDR3_DQS_DN(8)  BI  = M_K_DQS_DN<8>
  DF69  VSS(225)  GROUND  = GND
  DF71  DDR5_DQ(20)  BI  = M_M_DQ<20>
  DF73  VSS(224)  GROUND  = GND
  DF75  DDR5_DQS_DN(10)  BI  = M_M_DQS_DN<10>
  DF77  DDR5_DQ(14)  BI  = M_M_DQ<14>
  DF79  VSS(223)  GROUND  = GND
  DF81  DDR4_DQ(11)  BI  = M_L_DQ<11>
  DF83  VSS(222)  GROUND  = GND
  DF85  VSS(221)  GROUND  = GND
  DG2  VSS(220)  GROUND  = GND
  DG4  PE1_TX_DN(4)  OUT  = TP_P3E_CPU1_PE1_MP_TXN<4>
  DG6  PE3_TX_DP(12)  OUT  = P3E_CPU1_PE3_MP_TXP<12>
  DG8  VCCIO(54)  POWER  = PVCCIO_CPU1
  DG10  PE3_RX_DN(11)  IN  = P3E_CPU1_PE3_MP_RXN<11>
  DG12  PE3_RX_DN(10)  IN  = P3E_CPU1_PE3_MP_RXN<10>
  DG14  VSS(218)  GROUND  = GND
  DG16  VSS(217)  GROUND  = GND
  DG18  UPI2_TX_DN(6)  OUT  = TP_CPU1_UPI2_RSVD_CM13
  DG20  UPI2_TX_DN(3)  OUT  = TP_CPU1_UPI2_RSVD_CH11
  DG22  UPI2_RX_DP(0)  IN  = GND
  DG24  VSS(216)  GROUND  = GND
  DG26  DDR4_DQS_DN(16)  BI  = M_L_DQS_DN<16>
  DG28  DDR4_DQ(60)  BI  = M_L_DQ<60>
  DG30  DDR5_DQ(42)  BI  = M_M_DQ<42>
  DG32  DDR5_DQS_DN(14)  BI  = M_M_DQS_DN<14>
  DG34  DDR5_DQ(44)  BI  = M_M_DQ<44>
  DG36  RSVD(44)  BI  = TP_CPU1_RSVD_44
  DG38  DDR5_DQ(35)  BI  = M_M_DQ<35>
  DG40  DDR5_DQS_DN(4)  BI  = M_M_DQS_DN<4>
  DG42  DDR5_DQ(33)  BI  = M_M_DQ<33>
  DG44  SVIDCLK(1)  OUT  = SVID_CLK1_CPU1
  DG46  DDR5_CS_N(3)  OUT  = M_M_CS_N<3>
  DG48  DDR5_ODT(1)  OUT  = M_M_ODT<1>
  DG50  DDR5_ODT(0)  OUT  = M_M_ODT<0>
  DG52  DDR5_MA(16)  OUT  = M_M_MA<16>
  DG54  DDR5_CLK_DP(1)  OUT  = M_M_CLK_DP<1>
  DG56  DDR5_CLK_DP(3)  OUT  = M_M_CLK_DP<3>
  DG58  DDR5_MA(3)  OUT  = M_M_MA<3>
  DG60  DDR5_MA(12)  OUT  = M_M_MA<12>
  DG62  DDR5_CKE(0)  OUT  = M_M_CKE<0>
  DG64  RSVD(43)  BI  = TP_CPU1_RSVD_43
  DG66  VSS(215)  GROUND  = GND
  DG68  VSS(214)  GROUND  = GND
  DG70  DDR5_DQ(16)  BI  = M_M_DQ<16>
  DG72  DDR5_DQ(21)  BI  = M_M_DQ<21>
  DG74  DDR5_DQS_DP(10)  BI  = M_M_DQS_DP<10>
  DG76  VSS(213)  GROUND  = GND
  DG78  VSS(212)  GROUND  = GND
  DG80  VSS(211)  GROUND  = GND
  DG82  VSS(210)  GROUND  = GND
  DG84  DDR3_DQ(8)  BI  = M_K_DQ<8>
  DH3  PE1_TX_DP(5)  OUT  = TP_P3E_CPU1_PE1_MP_TXP<5>
  DH5  PE3_TX_DP(11)  OUT  = P3E_CPU1_PE3_MP_TXP<11>
  DH7  VCCIO(55)  POWER  = PVCCIO_CPU1
  DH9  PE1_RX_DN(5)  IN  = TP_P3E_CPU1_PE1_MP_RXN<5>
  DH11  PE3_RX_DP(9)  IN  = P3E_CPU1_PE3_MP_RXP<9>
  DH13  VSS(209)  GROUND  = GND
  DH15  VSS(208)  GROUND  = GND
  DH17  UPI2_TX_DP(5)  OUT  = TP_CPU1_UPI2_RSVD_CH13
  DH19  UPI2_TX_DN(4)  OUT  = TP_CPU1_UPI2_RSVD_CF13
  DH21  VSS(102)  GROUND  = GND
  DH23  VSS(207)  GROUND  = GND
  DH25  VSS(206)  GROUND  = GND
  DH27  VSS(205)  GROUND  = GND
  DH29  VSS(204)  GROUND  = GND
  DH31  VSS(203)  GROUND  = GND
  DH33  VSS(202)  GROUND  = GND
  DH35  VSS(201)  GROUND  = GND
  DH37  VSS(200)  GROUND  = GND
  DH39  DDR5_DQ(39)  BI  = M_M_DQ<39>
  DH41  VSS(199)  GROUND  = GND
  DH45  VCCD345(41)  POWER  = PVDDQ_KLM
  DH47  VCCD345(40)  POWER  = PVDDQ_KLM
  DH49  VCCD345(39)  POWER  = PVDDQ_KLM
  DH51  VCCD345(38)  POWER  = PVDDQ_KLM
  DH53  VCCD345(37)  POWER  = PVDDQ_KLM
  DH55  VCCD345(36)  POWER  = PVDDQ_KLM
  DH57  VCCD345(35)  POWER  = PVDDQ_KLM
  DH59  VCCD345(34)  POWER  = PVDDQ_KLM
  DH61  VCCD345(33)  POWER  = PVDDQ_KLM
  DH63  VCCD345(32)  POWER  = PVDDQ_KLM
  DH65  RSVD(42)  BI  = TP_CPU1_RSVD_42
  DH67  VSS(198)  GROUND  = GND
  DH69  DDR5_DQS_DP(11)  BI  = M_M_DQS_DP<11>
  DH71  VSS(197)  GROUND  = GND
  DH73  VSS(196)  GROUND  = GND
  DH75  DDR5_DQ(10)  BI  = M_M_DQ<10>
  DH77  DDR5_DQ(15)  BI  = M_M_DQ<15>
  DH79  VSS(195)  GROUND  = GND
  DH81  VSS(194)  GROUND  = GND
  DH83  VSS(193)  GROUND  = GND
  DH85  DDR3_DQ(9)  BI  = M_K_DQ<9>
  DJ2  VSS(192)  GROUND  = GND
  DJ4  PE3_TX_DN(11)  OUT  = P3E_CPU1_PE3_MP_TXN<11>
  DJ6  PE3_TX_DN(12)  OUT  = P3E_CPU1_PE3_MP_TXN<12>
  DJ8  PE1_RX_DP(6)  IN  = TP_P3E_CPU1_PE1_MP_RXP<6>
  DJ10  VSS(191)  GROUND  = GND
  DJ12  PE3_RX_DN(9)  IN  = P3E_CPU1_PE3_MP_RXN<9>
  DJ14  PE3_RX_DP(7)  IN  = P3E_CPU1_PE3_MP_RXP<7>
  DJ16  VCCIO(60)  POWER  = PVCCIO_CPU1
  DJ18  UPI2_TX_DP(4)  OUT  = TP_CPU1_UPI2_RSVD_CG12
  DJ20  UPI2_TX_DP(3)  OUT  = TP_CPU1_UPI2_RSVD_CF11
  DJ22  VSS(189)  GROUND  = GND
  DJ24  DDR4_DQ(59)  BI  = M_L_DQ<59>
  DJ26  DDR4_DQS_DP(7)  BI  = M_L_DQS_DP<7>
  DJ28  DDR4_DQ(61)  BI  = M_L_DQ<61>
  DJ30  DDR5_DQ(43)  BI  = M_M_DQ<43>
  DJ32  DDR5_DQS_DP(5)  BI  = M_M_DQS_DP<5>
  DJ34  DDR5_DQ(45)  BI  = M_M_DQ<45>
  DJ36  RSVD(41)  BI  = TP_CPU1_RSVD_41
  DJ38  VSS(188)  GROUND  = GND
  DJ40  DDR5_DQS_DP(4)  BI  = M_M_DQS_DP<4>
  DJ42  VSS(187)  GROUND  = GND
  DJ44  SVIDDATA(1)  BI  = SVID_DIO1_CPU1
  DJ46  DDR5_CS_N(2)  OUT  = M_M_CS_N<2>
  DJ48  DDR5_CS_N(5)  OUT  = M_M_CS_N<5>
  DJ50  DDR5_MA(14)  OUT  = M_M_MA<14>
  DJ52  DDR5_BA(0)  OUT  = M_M_BA<0>
  DJ54  DDR5_CLK_DP(0)  OUT  = M_M_CLK_DP<0>
  DJ56  DDR5_CLK_DP(2)  OUT  = M_M_CLK_DP<2>
  DJ58  DDR5_MA(4)  OUT  = M_M_MA<4>
  DJ60  DDR4_MA(8)  OUT  = M_L_MA<8>
  DJ62  DDR4_BG(0)  OUT  = M_L_BG<0>
  DJ64  VCCD345(31)  POWER  = PVDDQ_KLM
  DJ66  RSVD(40)  BI  = TP_CPU1_RSVD_40
  DJ68  VSS(186)  GROUND  = GND
  DJ70  DDR5_DQS_DN(11)  BI  = M_M_DQS_DN<11>
  DJ72  DDR5_DQ(17)  BI  = M_M_DQ<17>
  DJ74  VSS(185)  GROUND  = GND
  DJ76  DDR5_DQ(11)  BI  = M_M_DQ<11>
  DJ78  VSS(184)  GROUND  = GND
  DJ80  DDR3_DQ(21)  BI  = M_K_DQ<21>
  DJ82  VSS(183)  GROUND  = GND
  DJ84  VSS(182)  GROUND  = GND
  DK3  PE1_TX_DN(5)  OUT  = TP_P3E_CPU1_PE1_MP_TXN<5>
  DK5  PE3_TX_DP(10)  OUT  = P3E_CPU1_PE3_MP_TXP<10>
  DK7  VSS(181)  GROUND  = GND
  DK9  PE1_RX_DN(6)  IN  = TP_P3E_CPU1_PE1_MP_RXN<6>
  DK11  PE1_RX_DP(8)  IN  = TP_P3E_CPU1_PE1_RSR3_RXP<8>
  DK13  PE3_RX_DP(8)  IN  = P3E_CPU1_PE3_MP_RXP<8>
  DK15  RSVD(39)  BI  = TP_CPU1_RSVD_39
  DK17  UPI2_TX_DN(5)  OUT  = TP_CPU1_UPI2_RSVD_CJ14
  DK19  UPI2_TX_DP(2)  OUT  = TP_CPU1_UPI2_RSVD_CD11
  DK21  VCCIO(8)  POWER  = PVCCIO_CPU1
  DK23  VSS(180)  GROUND  = GND
  DK25  DDR4_DQ(63)  BI  = M_L_DQ<63>
  DK27  DDR4_DQ(57)  BI  = M_L_DQ<57>
  DK29  VSS(179)  GROUND  = GND
  DK31  DDR5_DQ(47)  BI  = M_M_DQ<47>
  DK33  DDR5_DQ(41)  BI  = M_M_DQ<41>
  DK35  VSS(178)  GROUND  = GND
  DK37  RSVD(38)  BI  = TP_CPU1_RSVD_38
  DK39  VSS(177)  GROUND  = GND
  DK41  VSS(176)  GROUND  = GND
  DK45  DDR5_CS_N(7)  OUT  = M_M_CS_N<7>
  DK47  DDR4_CS_N(3)  OUT  = M_L_CS_N<3>
  DK49  DDR5_ODT(2)  OUT  = M_M_ODT<2>
  DK51  DDR5_CS_N(0)  OUT  = M_M_CS_N<0>
  DK53  DDR5_PAR  OUT  = M_M_PAR
  DK55  DDR5_CLK_DN(0)  OUT  = M_M_CLK_DN<0>
  DK57  DDR5_CLK_DN(2)  OUT  = M_M_CLK_DN<2>
  DK59  DDR5_MA(6)  OUT  = M_M_MA<6>
  DK61  DDR4_MA(7)  OUT  = M_L_MA<7>
  DK63  DDR5_CKE(2)  OUT  = M_M_CKE<2>
  DK65  RSVD(37)  BI  = TP_CPU1_RSVD_37
  DK67  RSVD(36)  BI  = TP_CPU1_RSVD_36
  DK69  DDR5_DQ(22)  BI  = M_M_DQ<22>
  DK71  DDR5_DQS_DP(2)  BI  = M_M_DQS_DP<2>
  DK73  VSS(175)  GROUND  = GND
  DK75  VSS(174)  GROUND  = GND
  DK77  VSS(173)  GROUND  = GND
  DK79  DDR3_DQ(20)  BI  = M_K_DQ<20>
  DK81  DDR3_DQ(17)  BI  = M_K_DQ<17>
  DK83  VSS(172)  GROUND  = GND
  DK85  VSS(171)  GROUND  = GND
  DL2  PE1_TX_DP(6)  OUT  = TP_P3E_CPU1_PE1_MP_TXP<6>
  DL4  VSS(168)  GROUND  = GND
  DL6  PE3_TX_DN(10)  OUT  = P3E_CPU1_PE3_MP_TXN<10>
  DL8  VSS(1201)  GROUND  = GND
  DL10  PE1_RX_DP(7)  IN  = TP_P3E_CPU1_PE1_MP_RXP<7>
  DL12  PE3_RX_DN(8)  IN  = P3E_CPU1_PE3_MP_RXN<8>
  DL14  PE3_RX_DN(7)  IN  = P3E_CPU1_PE3_MP_RXN<7>
  DL16  VSS(170)  GROUND  = GND
